(kicad_pcb
	(version 20240108)
	(generator "pcbnew")
	(generator_version "8.0")
	(general
		(thickness 1.586)
		(legacy_teardrops no)
	)
	(paper "A4")
	(title_block
		(title "GMSL Serializer")
		(date "2024-11-27")
		(rev "1.1.1")
		(company "Antmicro Ltd")
		(comment 1 "www.antmicro.com")
		(comment 9 "footprints 1-3 of 117")
	)
	(layers
		(0 "F.Cu" signal)
		(1 "In1.Cu" power)
		(2 "In2.Cu" power)
		(31 "B.Cu" signal)
		(32 "B.Adhes" user "B.Adhesive")
		(33 "F.Adhes" user "F.Adhesive")
		(34 "B.Paste" user)
		(35 "F.Paste" user)
		(36 "B.SilkS" user "B.Silkscreen")
		(37 "F.SilkS" user "F.Silkscreen")
		(38 "B.Mask" user)
		(39 "F.Mask" user)
		(40 "Dwgs.User" user "User.Drawings")
		(41 "Cmts.User" user "User.Comments")
		(42 "Eco1.User" user "User.Eco1")
		(43 "Eco2.User" user "User.Eco2")
		(44 "Edge.Cuts" user)
		(45 "Margin" user)
		(46 "B.CrtYd" user "B.Courtyard")
		(47 "F.CrtYd" user "F.Courtyard")
		(48 "B.Fab" user)
		(49 "F.Fab" user)
	)
	(footprint "antmicro-footprints:R_0402_1005Metric"
		(layer "F.Cu")
		(at 135.4 110.95)
		(descr "Resistor SMD 0402")
		(tags "resistor SMD 0402")
		(property "Reference" "R31"
			(at 0.9 0.3375 0)
			(layer "F.SilkS")
			(effects
				(font
					(size 0.7 0.7)
					(thickness 0.15)
				)
				(justify left bottom)
			)
		)
		(property "Value" "R_0R_0402"
			(at -1.011843 1.772047 0)
			(layer "F.Fab")
			(effects
				(font
					(size 0.7 0.7)
					(thickness 0.15)
				)
				(justify left bottom)
			)
		)
		(property "Footprint" "antmicro-footprints:R_0402_1005Metric"
			(at 0 0 0)
			(layer "F.Fab")
			(hide yes)
			(effects
				(font
					(size 1.27 1.27)
					(thickness 0.15)
				)
			)
		)
		(property "Datasheet" "https://industrial.panasonic.com/cdbs/www-data/pdf/RDA0000/AOA0000C301.pdf"
			(at 0 0 0)
			(layer "F.Fab")
			(hide yes)
			(effects
				(font
					(size 1.27 1.27)
					(thickness 0.15)
				)
			)
		)
		(property "Author" "Antmicro"
			(at 0 0 0)
			(layer "F.Fab")
			(hide yes)
			(effects
				(font
					(size 1 1)
					(thickness 0.15)
				)
			)
		)
		(property "Current" "1A"
			(at 0 0 0)
			(layer "F.Fab")
			(hide yes)
			(effects
				(font
					(size 1 1)
					(thickness 0.15)
				)
			)
		)
		(property "License" "Apache-2.0"
			(at 0 0 0)
			(layer "F.Fab")
			(hide yes)
			(effects
				(font
					(size 1 1)
					(thickness 0.15)
				)
			)
		)
		(property "MPN" "ERJ2GE0R00X"
			(at 0 0 0)
			(layer "F.Fab")
			(hide yes)
			(effects
				(font
					(size 1 1)
					(thickness 0.15)
				)
			)
		)
		(property "Manufacturer" "Panasonic"
			(at 0 0 0)
			(layer "F.Fab")
			(hide yes)
			(effects
				(font
					(size 1 1)
					(thickness 0.15)
				)
			)
		)
		(property "Tolerance" ""
			(at 0 0 0)
			(layer "F.Fab")
			(hide yes)
			(effects
				(font
					(size 1 1)
					(thickness 0.15)
				)
			)
		)
		(property "Val" "0R"
			(at 0 0 0)
			(layer "F.Fab")
			(hide yes)
			(effects
				(font
					(size 1 1)
					(thickness 0.15)
				)
			)
		)
		(sheetname "Serializer")
		(sheetfile "serializer.kicad_sch")
		(attr smd exclude_from_bom dnp)
		(fp_rect
			(start -0.925 -0.47)
			(end 0.925 0.47)
			(stroke
				(width 0.05)
				(type default)
			)
			(fill none)
			(layer "F.CrtYd")
		)
		(fp_rect
			(start -0.5 -0.25)
			(end 0.5 0.25)
			(stroke
				(width 0.15)
				(type solid)
			)
			(fill none)
			(layer "F.Fab")
		)
		(fp_text user "License: Apache-2.0"
			(at -0.95 5.169 0)
			(layer "F.Fab")
			(hide yes)
			(effects
				(font
					(size 0.7 0.7)
					(thickness 0.15)
				)
				(justify left bottom)
			)
		)
		(fp_text user "${REFERENCE}"
			(at -0.95 3.168 0)
			(layer "F.Fab")
			(hide yes)
			(effects
				(font
					(size 0.7 0.7)
					(thickness 0.15)
				)
				(justify left bottom)
			)
		)
		(fp_text user "Author: Antmicro"
			(at -0.95 4.169 0)
			(layer "F.Fab")
			(hide yes)
			(effects
				(font
					(size 0.7 0.7)
					(thickness 0.15)
				)
				(justify left bottom)
			)
		)
		(pad "1" smd roundrect
			(at -0.48 0)
			(size 0.59 0.64)
			(layers "F.Cu" "F.Paste" "F.Mask")
			(roundrect_rratio 0.25)
			(net 89 "/CSI Connector/I2C.SCL")
			(pintype "passive")
		)
		(pad "2" smd roundrect
			(at 0.48 0)
			(size 0.59 0.64)
			(layers "F.Cu" "F.Paste" "F.Mask")
			(roundrect_rratio 0.25)
			(net 79 "Net-(U6-MFP8)")
			(pintype "passive")
		)
	)
	(footprint "antmicro-footprints:C_0402_1005Metric"
		(layer "F.Cu")
		(at 131.12 84.881 -90)
		(descr "Capacitor SMD 0402")
		(tags "capacitor SMD 0402")
		(property "Reference" "C3"
			(at -0.73 0.589 90)
			(layer "F.SilkS")
			(effects
				(font
					(size 0.7 0.7)
					(thickness 0.15)
				)
				(justify right bottom)
			)
		)
		(property "Value" "C_220n_0402"
			(at -1.022927 2.155213 90)
			(layer "F.Fab")
			(effects
				(font
					(size 0.7 0.7)
					(thickness 0.15)
				)
				(justify right bottom)
			)
		)
		(property "Footprint" "antmicro-footprints:C_0402_1005Metric"
			(at 0 0 -90)
			(layer "F.Fab")
			(hide yes)
			(effects
				(font
					(size 1.27 1.27)
					(thickness 0.15)
				)
			)
		)
		(property "Datasheet" "https://www.yageo.com/en/Chart/Download/pdf/CC0402KRX5R6BB224"
			(at 0 0 -90)
			(layer "F.Fab")
			(hide yes)
			(effects
				(font
					(size 1.27 1.27)
					(thickness 0.15)
				)
			)
		)
		(property "Author" "Antmicro"
			(at 48.159 217.621 0)
			(layer "F.Fab")
			(hide yes)
			(effects
				(font
					(size 1 1)
					(thickness 0.15)
				)
			)
		)
		(property "Dielectric" ""
			(at 48.159 217.621 0)
			(layer "F.Fab")
			(hide yes)
			(effects
				(font
					(size 1 1)
					(thickness 0.15)
				)
			)
		)
		(property "License" "Apache-2.0"
			(at 48.159 217.621 0)
			(layer "F.Fab")
			(hide yes)
			(effects
				(font
					(size 1 1)
					(thickness 0.15)
				)
			)
		)
		(property "MPN" "CC0402KRX5R6BB224"
			(at 48.159 217.621 0)
			(layer "F.Fab")
			(hide yes)
			(effects
				(font
					(size 1 1)
					(thickness 0.15)
				)
			)
		)
		(property "Manufacturer" "YAGEO"
			(at 48.159 217.621 0)
			(layer "F.Fab")
			(hide yes)
			(effects
				(font
					(size 1 1)
					(thickness 0.15)
				)
			)
		)
		(property "Val" "220n"
			(at 48.159 217.621 0)
			(layer "F.Fab")
			(hide yes)
			(effects
				(font
					(size 1 1)
					(thickness 0.15)
				)
			)
		)
		(property "Voltage" ""
			(at 48.159 217.621 0)
			(layer "F.Fab")
			(hide yes)
			(effects
				(font
					(size 1 1)
					(thickness 0.15)
				)
			)
		)
		(sheetname "Supply")
		(sheetfile "supply.kicad_sch")
		(attr smd)
		(fp_rect
			(start -0.925 -0.47)
			(end 0.925 0.47)
			(stroke
				(width 0.05)
				(type default)
			)
			(fill none)
			(layer "F.CrtYd")
		)
		(fp_line
			(start -0.494 0.248)
			(end -0.494 -0.25)
			(stroke
				(width 0.15)
				(type solid)
			)
			(layer "F.Fab")
		)
		(fp_line
			(start 0.504 0.248)
			(end -0.494 0.248)
			(stroke
				(width 0.15)
				(type solid)
			)
			(layer "F.Fab")
		)
		(fp_line
			(start -0.494 -0.25)
			(end 0.504 -0.25)
			(stroke
				(width 0.15)
				(type solid)
			)
			(layer "F.Fab")
		)
		(fp_line
			(start 0.504 -0.25)
			(end 0.504 0.248)
			(stroke
				(width 0.15)
				(type solid)
			)
			(layer "F.Fab")
		)
		(fp_text user "Author: Antmicro"
			(at -0.939 3.399 90)
			(layer "F.Fab")
			(hide yes)
			(effects
				(font
					(size 0.7 0.7)
					(thickness 0.15)
				)
				(justify right bottom)
			)
		)
		(fp_text user "${REFERENCE}"
			(at -0.939 4.599 90)
			(layer "F.Fab")
			(hide yes)
			(effects
				(font
					(size 0.7 0.7)
					(thickness 0.15)
				)
				(justify right bottom)
			)
		)
		(fp_text user "License: Apache-2.0"
			(at -0.939 5.799 90)
			(layer "F.Fab")
			(hide yes)
			(effects
				(font
					(size 0.7 0.7)
					(thickness 0.15)
				)
				(justify right bottom)
			)
		)
		(pad "1" smd roundrect
			(at -0.48 0 270)
			(size 0.59 0.64)
			(layers "F.Cu" "F.Paste" "F.Mask")
			(roundrect_rratio 0.25)
			(net 3 "Net-(U1-BST)")
			(pintype "passive")
		)
		(pad "2" smd roundrect
			(at 0.48 0 270)
			(size 0.59 0.64)
			(layers "F.Cu" "F.Paste" "F.Mask")
			(roundrect_rratio 0.25)
			(net 4 "/Supply/SW_5V")
			(pintype "passive")
		)
	)
	(footprint "antmicro-footprints:R_0603_1608Metric"
		(layer "F.Cu")
		(at 164.4 106.3 -90)
		(descr "Resistor SMD 0603")
		(tags "resistor SMD 0603")
		(property "Reference" "R14"
			(at -0.675 -1.4976 90)
			(layer "F.SilkS")
			(effects
				(font
					(size 0.7 0.7)
					(thickness 0.15)
				)
				(justify right bottom)
			)
		)
		(property "Value" "R_0R_22.4A_0603"
			(at 0 1.6 90)
			(layer "F.Fab")
			(effects
				(font
					(size 0.7 0.7)
					(thickness 0.15)
				)
				(justify right bottom)
			)
		)
		(property "Footprint" "antmicro-footprints:R_0603_1608Metric"
			(at 0 0 -90)
			(layer "F.Fab")
			(hide yes)
			(effects
				(font
					(size 1.27 1.27)
					(thickness 0.15)
				)
			)
		)
		(property "Datasheet" "https://fscdn.rohm.com/en/products/databook/datasheet/passive/resistor/chip_resistor/pmr-jpw-e.pdf"
			(at 0 0 -90)
			(layer "F.Fab")
			(hide yes)
			(effects
				(font
					(size 1.27 1.27)
					(thickness 0.15)
				)
			)
		)
		(property "Author" "Antmicro"
			(at 58.1 270.7 0)
			(layer "F.Fab")
			(hide yes)
			(effects
				(font
					(size 1 1)
					(thickness 0.15)
				)
			)
		)
		(property "License" "Apache-2.0"
			(at 58.1 270.7 0)
			(layer "F.Fab")
			(hide yes)
			(effects
				(font
					(size 1 1)
					(thickness 0.15)
				)
			)
		)
		(property "MPN" "PMR03EZPJ000"
			(at 58.1 270.7 0)
			(layer "F.Fab")
			(hide yes)
			(effects
				(font
					(size 1 1)
					(thickness 0.15)
				)
			)
		)
		(property "Manufacturer" "ROHM Semiconductor"
			(at 58.1 270.7 0)
			(layer "F.Fab")
			(hide yes)
			(effects
				(font
					(size 1 1)
					(thickness 0.15)
				)
			)
		)
		(property "Max. Curr." "22.4A"
			(at 58.1 270.7 0)
			(layer "F.Fab")
			(hide yes)
			(effects
				(font
					(size 1 1)
					(thickness 0.15)
				)
			)
		)
		(property "Tolerance" "template_tolerance"
			(at 58.1 270.7 0)
			(layer "F.Fab")
			(hide yes)
			(effects
				(font
					(size 1 1)
					(thickness 0.15)
				)
			)
		)
		(property "Val" "0R"
			(at 58.1 270.7 0)
			(layer "F.Fab")
			(hide yes)
			(effects
				(font
					(size 1 1)
					(thickness 0.15)
				)
			)
		)
		(sheetname "Supply")
		(sheetfile "supply.kicad_sch")
		(attr smd)
		(fp_line
			(start -0.15 0.4)
			(end 0.15 0.4)
			(stroke
				(width 0.15)
				(type solid)
			)
			(layer "F.SilkS")
		)
		(fp_line
			(start -0.15 -0.4)
			(end 0.15 -0.4)
			(stroke
				(width 0.15)
				(type solid)
			)
			(layer "F.SilkS")
		)
		(fp_rect
			(start -1.25 -0.65)
			(end 1.25 0.65)
			(stroke
				(width 0.05)
				(type solid)
			)
			(fill none)
			(layer "F.CrtYd")
		)
		(fp_rect
			(start -0.8 -0.4)
			(end 0.8 0.4)
			(stroke
				(width 0.15)
				(type solid)
			)
			(fill none)
			(layer "F.Fab")
		)
		(fp_text user "${REFERENCE}"
			(at -1.25 3.898 90)
			(layer "F.Fab")
			(hide yes)
			(effects
				(font
					(size 0.7 0.7)
					(thickness 0.15)
				)
				(justify right bottom)
			)
		)
		(fp_text user "License: Apache-2.0"
			(at -1.25 5.9 90)
			(layer "F.Fab")
			(hide yes)
			(effects
				(font
					(size 0.7 0.7)
					(thickness 0.15)
				)
				(justify right bottom)
			)
		)
		(fp_text user "Author: Antmicro"
			(at -1.25 4.9 90)
			(layer "F.Fab")
			(hide yes)
			(effects
				(font
					(size 0.7 0.7)
					(thickness 0.15)
				)
				(justify right bottom)
			)
		)
		(pad "1" smd roundrect
			(at -0.7 0 270)
			(size 0.8 1)
			(layers "F.Cu" "F.Paste" "F.Mask")
			(roundrect_rratio 0.2)
			(net 8 "/Supply/OUT_1V8")
			(pintype "passive")
		)
		(pad "2" smd roundrect
			(at 0.7 0 270)
			(size 0.8 1)
			(layers "F.Cu" "F.Paste" "F.Mask")
			(roundrect_rratio 0.2)
			(net 11 "+1V8")
			(pintype "passive")
		)
	)
)
